FILE_TYPE = CONNECTIVITY;
{Allegro Design Entry HDL 17.2-2016 S081 (4005846) 1/11/2022}
"PAGE_NUMBER" = 251;
0"NC";
END.
